# BASEBOARD_FAB2 (Tioga Pass) — schematic netlist excerpt (pin names and nets, part order shuffled) for the footprints in the layout excerpt that follows; sources: Cadence DE-HDL packaged netlist, KiCad conversion of Wiwynn_Tioga_Pass_MB.brd

J1B1  SCONN288_H44441004  SCONN  pkg PIP  page 83
  \12v\(1)  = P12V_NVDIMM_KLM
  VSS(93)  = GND
  DQ(4)  = M_K_DQ<5>
  VSS(92)  = GND
  DQ(0)  = M_K_DQ<1>
  VSS(91)  = GND
  DQS9P  = M_K_DQS_DP<9>
  DQS9N  = M_K_DQS_DN<9>
  VSS(90)  = GND
  DQ(6)  = M_K_DQ<7>
  VSS(89)  = GND
  DQ(2)  = M_K_DQ<3>
  VSS(88)  = GND
  DQ(12)  = M_K_DQ<13>
  VSS(87)  = GND
  DQ(8)  = M_K_DQ<9>
  VSS(86)  = GND
  DQS10P  = M_K_DQS_DP<10>
  DQS10N  = M_K_DQS_DN<10>
  VSS(85)  = GND
  DQ(14)  = M_K_DQ<15>
  VSS(84)  = GND
  DQ(10)  = M_K_DQ<11>
  VSS(83)  = GND
  DQ(20)  = M_K_DQ<21>
  VSS(82)  = GND
  DQ(16)  = M_K_DQ<17>
  VSS(81)  = GND
  DQS11P  = M_K_DQS_DP<11>
  DQS11N  = M_K_DQS_DN<11>
  VSS(80)  = GND
  DQ(22)  = M_K_DQ<23>
  VSS(79)  = GND
  DQ(18)  = M_K_DQ<19>
  VSS(78)  = GND
  DQ(28)  = M_K_DQ<29>
  VSS(77)  = GND
  DQ(24)  = M_K_DQ<25>
  VSS(76)  = GND
  DQS12P  = M_K_DQS_DP<12>
  DQS12N  = M_K_DQS_DN<12>
  VSS(75)  = GND
  DQ(30)  = M_K_DQ<31>
  VSS(74)  = GND
  DQ(26)  = M_K_DQ<27>
  VSS(73)  = GND
  CB(4)  = M_K_ECC<5>
  VSS(72)  = GND
  CB(0)  = M_K_ECC<1>
  VSS(71)  = GND
  DQS17P  = M_K_DQS_DP<17>
  DQS17N  = M_K_DQS_DN<17>
  VSS(70)  = GND
  CB(6)  = M_K_ECC<7>
  VSS(69)  = GND
  CB(2)  = M_K_ECC<3>
  VSS(68)  = GND
  RESET_N  = M_KLM_RST_N
  VDD(25)  = PVDDQ_KLM
  CKE(0)  = M_K_CKE<0>
  VDD(24)  = PVDDQ_KLM
  ACT_N  = M_K_ACT_N
  BG(0)  = M_K_BG<0>
  VDD(23)  = PVDDQ_KLM
  A12  = M_K_MA<12>
  A9  = M_K_MA<9>
  VDD(22)  = PVDDQ_KLM
  A8  = M_K_MA<8>
  A6  = M_K_MA<6>
  VDD(21)  = PVDDQ_KLM
  A3  = M_K_MA<3>
  A1  = M_K_MA<1>
  VDD(20)  = PVDDQ_KLM
  CK0P  = M_K_CLK_DP<0>
  CK0N  = M_K_CLK_DN<0>
  VDD(19)  = PVDDQ_KLM
  VTT(1)  = PVTT_KLM
  EVENT_N  = FM_DIMM_EVENT_COD_N
  A0  = M_K_MA<0>
  VDD(18)  = PVDDQ_KLM
  BA(0)  = M_K_BA<0>
  A16_RAS_N  = M_K_MA<16>
  VDD(17)  = PVDDQ_KLM
  S0_N  = M_K_CS_N<0>
  VDD(16)  = PVDDQ_KLM
  A15_CAS_N  = M_K_MA<15>
  ODT(0)  = M_K_ODT<0>
  VDD(15)  = PVDDQ_KLM
  S1_N  = M_K_CS_N<1>
  VDD(14)  = PVDDQ_KLM
  ODT(1)  = M_K_ODT<1>
  VDD(13)  = PVDDQ_KLM
  S2_N_C(0)  = M_K_CS_N<2>
  VSS(67)  = GND
  DQ(36)  = M_K_DQ<37>
  VSS(66)  = GND
  DQ(32)  = M_K_DQ<33>
  VSS(65)  = GND
  DQS13P  = M_K_DQS_DP<13>
  DQS13N  = M_K_DQS_DN<13>
  VSS(64)  = GND
  DQ(38)  = M_K_DQ<39>
  VSS(63)  = GND
  DQ(34)  = M_K_DQ<35>
  VSS(62)  = GND
  DQ(44)  = M_K_DQ<45>
  VSS(61)  = GND
  DQ(40)  = M_K_DQ<41>
  VSS(60)  = GND
  DQS14P  = M_K_DQS_DP<14>
  DQS14N  = M_K_DQS_DN<14>
  VSS(59)  = GND
  DQ(46)  = M_K_DQ<47>
  VSS(58)  = GND
  DQ(42)  = M_K_DQ<43>
  VSS(57)  = GND
  DQ(52)  = M_K_DQ<53>
  VSS(56)  = GND
  DQ(48)  = M_K_DQ<49>
  VSS(55)  = GND
  DQS15P  = M_K_DQS_DP<15>
  DQS15N  = M_K_DQS_DN<15>
  VSS(54)  = GND
  DQ(54)  = M_K_DQ<55>
  VSS(53)  = GND
  DQ(50)  = M_K_DQ<51>
  VSS(52)  = GND
  DQ(60)  = M_K_DQ<61>
  VSS(51)  = GND
  DQ(56)  = M_K_DQ<57>
  VSS(50)  = GND
  DQS16P  = M_K_DQS_DP<16>
  DQS16N  = M_K_DQS_DN<16>
  VSS(49)  = GND
  DQ(62)  = M_K_DQ<63>
  VSS(48)  = GND
  DQ(58)  = M_K_DQ<59>
  VSS(47)  = GND
  SA(0)  = GND
  SA(1)  = GND
  SCL  = SMB_DDR_KLM_VPP_SCL
  VPP(4)  = PVPP_KLM
  VPP(3)  = PVPP_KLM
  RFU(2)  = TP_CH_K_DIMM_K0_RFU_2
  \12v\(0)  = P12V_NVDIMM_KLM
  VREFCA  = M_K_VREF
  VSS(46)  = GND
  DQ(5)  = M_K_DQ<4>
  VSS(45)  = GND
  DQ(1)  = M_K_DQ<0>
  VSS(44)  = GND
  DQS0N  = M_K_DQS_DN<0>
  DQS0P  = M_K_DQS_DP<0>
  VSS(43)  = GND
  DQ(7)  = M_K_DQ<6>
  VSS(42)  = GND
  DQ(3)  = M_K_DQ<2>
  VSS(41)  = GND
  DQ(13)  = M_K_DQ<12>
  VSS(40)  = GND
  DQ(9)  = M_K_DQ<8>
  VSS(39)  = GND
  DQS1N  = M_K_DQS_DN<1>
  DQS1P  = M_K_DQS_DP<1>
  VSS(38)  = GND
  DQ(15)  = M_K_DQ<14>
  VSS(37)  = GND
  DQ(11)  = M_K_DQ<10>
  VSS(36)  = GND
  DQ(21)  = M_K_DQ<20>
  VSS(35)  = GND
  DQ(17)  = M_K_DQ<16>
  VSS(34)  = GND
  DQS2N  = M_K_DQS_DN<2>
  DQS2P  = M_K_DQS_DP<2>
  VSS(33)  = GND
  DQ(23)  = M_K_DQ<22>
  VSS(32)  = GND
  DQ(19)  = M_K_DQ<18>
  VSS(31)  = GND
  DQ(29)  = M_K_DQ<28>
  VSS(30)  = GND
  DQ(25)  = M_K_DQ<24>
  VSS(29)  = GND
  DQS3N  = M_K_DQS_DN<3>
  DQS3P  = M_K_DQS_DP<3>
  VSS(28)  = GND
  DQ(31)  = M_K_DQ<30>
  VSS(27)  = GND
  DQ(27)  = M_K_DQ<26>
  VSS(26)  = GND
  CB(5)  = M_K_ECC<4>
  VSS(25)  = GND
  CB(1)  = M_K_ECC<0>
  VSS(24)  = GND
  DQS8N  = M_K_DQS_DN<8>
  DQS8P  = M_K_DQS_DP<8>
  VSS(23)  = GND
  CB(7)  = M_K_ECC<6>
  VSS(22)  = GND
  CB(3)  = M_K_ECC<2>
  VSS(21)  = GND
  CKE(1)  = M_K_CKE<1>
  VDD(12)  = PVDDQ_KLM
  RFU(0)  = TP_CH_K_DIMM_K0_RFU_0
  VDD(11)  = PVDDQ_KLM
  BG(1)  = M_K_BG<1>
  ALERT_N  = M_K_ALERT_N
  VDD(10)  = PVDDQ_KLM
  A11  = M_K_MA<11>
  A7  = M_K_MA<7>
  VDD(9)  = PVDDQ_KLM
  A5  = M_K_MA<5>
  A4  = M_K_MA<4>
  VDD(8)  = PVDDQ_KLM
  A2  = M_K_MA<2>
  VDD(7)  = PVDDQ_KLM
  CK1P  = M_K_CLK_DP<1>
  CK1N  = M_K_CLK_DN<1>
  VDD(6)  = PVDDQ_KLM
  VTT(0)  = PVTT_KLM
  PAR  = M_K_PAR
  VDD(5)  = PVDDQ_KLM
  BA(1)  = M_K_BA<1>
  A10  = M_K_MA<10>
  VDD(4)  = PVDDQ_KLM
  RFU(1)  = TP_CH_K_DIMM_K0_RFU_1
  A14_WE_N  = M_K_MA<14>
  VDD(3)  = PVDDQ_KLM
  SAVE_N_NC  = FM_ADR_COMPLETE_KLM_N
  VDD(2)  = PVDDQ_KLM
  A13  = M_K_MA<13>
  VDD(1)  = PVDDQ_KLM
  A17  = M_K_MA<17>
  C(2)  = M_K_C<2>
  VDD(0)  = PVDDQ_KLM
  S3_N_C(1)  = M_K_CS_N<3>
  SA(2)  = GND
  VSS(20)  = GND
  DQ(37)  = M_K_DQ<36>
  VSS(19)  = GND
  DQ(33)  = M_K_DQ<32>
  VSS(18)  = GND
  DQS4N  = M_K_DQS_DN<4>
  DQS4P  = M_K_DQS_DP<4>
  VSS(17)  = GND
  DQ(39)  = M_K_DQ<38>
  VSS(16)  = GND
  DQ(35)  = M_K_DQ<34>
  VSS(15)  = GND
  DQ(45)  = M_K_DQ<44>
  VSS(14)  = GND
  DQ(41)  = M_K_DQ<40>
  VSS(13)  = GND
  DQS5N  = M_K_DQS_DN<5>
  DQS5P  = M_K_DQS_DP<5>
  VSS(12)  = GND
  DQ(47)  = M_K_DQ<46>
  VSS(11)  = GND
  DQ(43)  = M_K_DQ<42>
  VSS(10)  = GND
  DQ(53)  = M_K_DQ<52>
  VSS(9)  = GND
  DQ(49)  = M_K_DQ<48>
  VSS(8)  = GND
  DQS6N  = M_K_DQS_DN<6>
  DQS6P  = M_K_DQS_DP<6>
  VSS(7)  = GND
  DQ(55)  = M_K_DQ<54>
  VSS(6)  = GND
  DQ(51)  = M_K_DQ<50>
  VSS(5)  = GND
  DQ(61)  = M_K_DQ<60>
  VSS(4)  = GND
  DQ(57)  = M_K_DQ<56>
  VSS(3)  = GND
  DQS7N  = M_K_DQS_DN<7>
  DQS7P  = M_K_DQS_DP<7>
  VSS(2)  = GND
  DQ(63)  = M_K_DQ<62>
  VSS(1)  = GND
  DQ(59)  = M_K_DQ<58>
  VSS(0)  = GND
  VDDSPD  = PVPP_KLM
  SDA  = SMB_DDR_KLM_VPP_SDA
  VPP(1)  = PVPP_KLM
  VPP(0)  = PVPP_KLM
  VPP(2)  = PVPP_KLM

(kicad_pcb
	(version 20260206)
	(generator "pcbnew")
	(generator_version "10.0")
	(general
		(thickness 1.6)
		(legacy_teardrops no)
	)
	(paper "A4")
	(title_block
		(title "Wiwynn_Tioga_Pass_MB.brd")
		(comment 1 "Tioga Pass / footprint 320 of 4770 (J1B1), pads 102-152 of 291")
	)
	(layers
		(0 "F.Cu" signal "TOP")
		(4 "In1.Cu" signal "L2GND")
		(6 "In2.Cu" signal "L3")
		(8 "In3.Cu" signal "L4GND")
		(10 "In4.Cu" signal "L5")
		(12 "In5.Cu" signal "L6GND")
		(14 "In6.Cu" signal "L7VCC")
		(16 "In7.Cu" signal "L8VCC")
		(18 "In8.Cu" signal "L9GND")
		(20 "In9.Cu" signal "L10")
		(22 "In10.Cu" signal "L11GND")
		(24 "In11.Cu" signal "L12")
		(26 "In12.Cu" signal "L13GND")
		(2 "B.Cu" signal "BOTTOM")
		(9 "F.Adhes" user "F.Adhesive")
		(11 "B.Adhes" user "B.Adhesive")
		(13 "F.Paste" user "Package Geometry/Pastemask Top")
		(15 "B.Paste" user "Package Geometry/Pastemask Bottom")
		(5 "F.SilkS" user "Ref Des/Silkscreen Top")
		(7 "B.SilkS" user "Ref Des/Silkscreen Bottom")
		(1 "F.Mask" user "Board Geometry/Soldermask Top")
		(3 "B.Mask" user "Board Geometry/Soldermask Bottom")
		(17 "Dwgs.User" user "User.Drawings")
		(19 "Cmts.User" user "User.Comments")
		(21 "Eco1.User" user "User.Eco1")
		(23 "Eco2.User" user "User.Eco2")
		(25 "Edge.Cuts" user "Board Geometry/Outline")
		(27 "Margin" user)
		(31 "F.CrtYd" user "Package Geometry/Place Bound Top")
		(29 "B.CrtYd" user "Package Geometry/Place Bound Bottom")
		(35 "F.Fab" user "Ref Des/Assembly Top")
		(33 "B.Fab" user "Ref Des/Assembly Bottom")
	)
	(footprint ""
		(layer "F.Cu")
		(at 29.699458 -133.0706 90)
		(property "Reference" "J1B1"
			(at -4.960112 38.372542 0)
			(unlocked yes)
			(layer "F.SilkS")
			(effects
				(font
					(size 0.7874 0.5842)
					(thickness 0.1524)
				)
				(justify left)
			)
		)
		(property "Value" ""
			(at 0 0 90)
			(layer "F.Fab")
			(effects
				(font
					(size 1.27 1.27)
				)
			)
		)
		(duplicate_pad_numbers_are_jumpers no)
		(pad "99" smd rect
			(at 0 88.399874 90)
			(size 1.8034 0.508)
			(layers "F.Cu" "F.Mask" "F.Paste")
			(net "M_K_DQS_DP<13>")
		)
		(pad "100" smd rect
			(at 0 89.250012 90)
			(size 1.8034 0.508)
			(layers "F.Cu" "F.Mask" "F.Paste")
			(net "M_K_DQS_DN<13>")
		)
		(pad "101" smd rect
			(at 0 90.099896 90)
			(size 1.8034 0.508)
			(layers "F.Cu" "F.Mask" "F.Paste")
			(net "GND")
		)
		(pad "102" smd rect
			(at 0 90.950034 90)
			(size 1.8034 0.508)
			(layers "F.Cu" "F.Mask" "F.Paste")
			(net "M_K_DQ<39>")
		)
		(pad "103" smd rect
			(at 0 91.799918 90)
			(size 1.8034 0.508)
			(layers "F.Cu" "F.Mask" "F.Paste")
			(net "GND")
		)
		(pad "104" smd rect
			(at 0 92.650056 90)
			(size 1.8034 0.508)
			(layers "F.Cu" "F.Mask" "F.Paste")
			(net "M_K_DQ<35>")
		)
		(pad "105" smd rect
			(at 0 93.49994 90)
			(size 1.8034 0.508)
			(layers "F.Cu" "F.Mask" "F.Paste")
			(net "GND")
		)
		(pad "106" smd rect
			(at 0 94.350078 90)
			(size 1.8034 0.508)
			(layers "F.Cu" "F.Mask" "F.Paste")
			(net "M_K_DQ<45>")
		)
		(pad "107" smd rect
			(at 0 95.199962 90)
			(size 1.8034 0.508)
			(layers "F.Cu" "F.Mask" "F.Paste")
			(net "GND")
		)
		(pad "108" smd rect
			(at 0 96.0501 90)
			(size 1.8034 0.508)
			(layers "F.Cu" "F.Mask" "F.Paste")
			(net "M_K_DQ<41>")
		)
		(pad "109" smd rect
			(at 0 96.899984 90)
			(size 1.8034 0.508)
			(layers "F.Cu" "F.Mask" "F.Paste")
			(net "GND")
		)
		(pad "110" smd rect
			(at 0 97.750122 90)
			(size 1.8034 0.508)
			(layers "F.Cu" "F.Mask" "F.Paste")
			(net "M_K_DQS_DP<14>")
		)
		(pad "111" smd rect
			(at 0 98.600006 90)
			(size 1.8034 0.508)
			(layers "F.Cu" "F.Mask" "F.Paste")
			(net "M_K_DQS_DN<14>")
		)
		(pad "112" smd rect
			(at 0 99.44989 90)
			(size 1.8034 0.508)
			(layers "F.Cu" "F.Mask" "F.Paste")
			(net "GND")
		)
		(pad "113" smd rect
			(at 0 100.300028 90)
			(size 1.8034 0.508)
			(layers "F.Cu" "F.Mask" "F.Paste")
			(net "M_K_DQ<47>")
		)
		(pad "114" smd rect
			(at 0 101.149912 90)
			(size 1.8034 0.508)
			(layers "F.Cu" "F.Mask" "F.Paste")
			(net "GND")
		)
		(pad "115" smd rect
			(at 0 102.00005 90)
			(size 1.8034 0.508)
			(layers "F.Cu" "F.Mask" "F.Paste")
			(net "M_K_DQ<43>")
		)
		(pad "116" smd rect
			(at 0 102.849934 90)
			(size 1.8034 0.508)
			(layers "F.Cu" "F.Mask" "F.Paste")
			(net "GND")
		)
		(pad "117" smd rect
			(at 0 103.700072 90)
			(size 1.8034 0.508)
			(layers "F.Cu" "F.Mask" "F.Paste")
			(net "M_K_DQ<53>")
		)
		(pad "118" smd rect
			(at 0 104.549956 90)
			(size 1.8034 0.508)
			(layers "F.Cu" "F.Mask" "F.Paste")
			(net "GND")
		)
		(pad "119" smd rect
			(at 0 105.400094 90)
			(size 1.8034 0.508)
			(layers "F.Cu" "F.Mask" "F.Paste")
			(net "M_K_DQ<49>")
		)
		(pad "120" smd rect
			(at 0 106.249978 90)
			(size 1.8034 0.508)
			(layers "F.Cu" "F.Mask" "F.Paste")
			(net "GND")
		)
		(pad "121" smd rect
			(at 0 107.100116 90)
			(size 1.8034 0.508)
			(layers "F.Cu" "F.Mask" "F.Paste")
			(net "M_K_DQS_DP<15>")
		)
		(pad "122" smd rect
			(at 0 107.95 90)
			(size 1.8034 0.508)
			(layers "F.Cu" "F.Mask" "F.Paste")
			(net "M_K_DQS_DN<15>")
		)
		(pad "123" smd rect
			(at 0 108.799884 90)
			(size 1.8034 0.508)
			(layers "F.Cu" "F.Mask" "F.Paste")
			(net "GND")
		)
		(pad "124" smd rect
			(at 0 109.650022 90)
			(size 1.8034 0.508)
			(layers "F.Cu" "F.Mask" "F.Paste")
			(net "M_K_DQ<55>")
		)
		(pad "125" smd rect
			(at 0 110.499906 90)
			(size 1.8034 0.508)
			(layers "F.Cu" "F.Mask" "F.Paste")
			(net "GND")
		)
		(pad "126" smd rect
			(at 0 111.350044 90)
			(size 1.8034 0.508)
			(layers "F.Cu" "F.Mask" "F.Paste")
			(net "M_K_DQ<51>")
		)
		(pad "127" smd rect
			(at 0 112.199928 90)
			(size 1.8034 0.508)
			(layers "F.Cu" "F.Mask" "F.Paste")
			(net "GND")
		)
		(pad "128" smd rect
			(at 0 113.050066 90)
			(size 1.8034 0.508)
			(layers "F.Cu" "F.Mask" "F.Paste")
			(net "M_K_DQ<61>")
		)
		(pad "129" smd rect
			(at 0 113.89995 90)
			(size 1.8034 0.508)
			(layers "F.Cu" "F.Mask" "F.Paste")
			(net "GND")
		)
		(pad "130" smd rect
			(at 0 114.750088 90)
			(size 1.8034 0.508)
			(layers "F.Cu" "F.Mask" "F.Paste")
			(net "M_K_DQ<57>")
		)
		(pad "131" smd rect
			(at 0 115.599972 90)
			(size 1.8034 0.508)
			(layers "F.Cu" "F.Mask" "F.Paste")
			(net "GND")
		)
		(pad "132" smd rect
			(at 0 116.45011 90)
			(size 1.8034 0.508)
			(layers "F.Cu" "F.Mask" "F.Paste")
			(net "M_K_DQS_DP<16>")
		)
		(pad "133" smd rect
			(at 0 117.299994 90)
			(size 1.8034 0.508)
			(layers "F.Cu" "F.Mask" "F.Paste")
			(net "M_K_DQS_DN<16>")
		)
		(pad "134" smd rect
			(at 0 118.149878 90)
			(size 1.8034 0.508)
			(layers "F.Cu" "F.Mask" "F.Paste")
			(net "GND")
		)
		(pad "135" smd rect
			(at 0 119.000016 90)
			(size 1.8034 0.508)
			(layers "F.Cu" "F.Mask" "F.Paste")
			(net "M_K_DQ<63>")
		)
		(pad "136" smd rect
			(at 0 119.8499 90)
			(size 1.8034 0.508)
			(layers "F.Cu" "F.Mask" "F.Paste")
			(net "GND")
		)
		(pad "137" smd rect
			(at 0 120.700038 90)
			(size 1.8034 0.508)
			(layers "F.Cu" "F.Mask" "F.Paste")
			(net "M_K_DQ<59>")
		)
		(pad "138" smd rect
			(at 0 121.549922 90)
			(size 1.8034 0.508)
			(layers "F.Cu" "F.Mask" "F.Paste")
			(net "GND")
		)
		(pad "139" smd rect
			(at 0 122.40006 90)
			(size 1.8034 0.508)
			(layers "F.Cu" "F.Mask" "F.Paste")
			(net "GND")
		)
		(pad "140" smd rect
			(at 0 123.249944 90)
			(size 1.8034 0.508)
			(layers "F.Cu" "F.Mask" "F.Paste")
			(net "GND")
		)
		(pad "141" smd rect
			(at 0 124.100082 90)
			(size 1.8034 0.508)
			(layers "F.Cu" "F.Mask" "F.Paste")
			(net "SMB_DDR_KLM_VPP_SCL")
		)
		(pad "142" smd rect
			(at 0 124.949966 90)
			(size 1.8034 0.508)
			(layers "F.Cu" "F.Mask" "F.Paste")
			(net "PVPP_KLM")
		)
		(pad "143" smd rect
			(at 0 125.800104 90)
			(size 1.8034 0.508)
			(layers "F.Cu" "F.Mask" "F.Paste")
			(net "PVPP_KLM")
		)
		(pad "144" smd rect
			(at 0 126.649988 90)
			(size 1.8034 0.508)
			(layers "F.Cu" "F.Mask" "F.Paste")
			(net "TP_CH_K_DIMM_K0_RFU_2")
		)
		(pad "145" smd rect
			(at 4.59994 0 90)
			(size 1.8034 0.508)
			(layers "F.Cu" "F.Mask" "F.Paste")
			(net "P12V_NVDIMM_KLM")
		)
		(pad "146" smd rect
			(at 4.59994 0.849884 90)
			(size 1.8034 0.508)
			(layers "F.Cu" "F.Mask" "F.Paste")
			(net "M_K_VREF")
		)
		(pad "147" smd rect
			(at 4.59994 1.700022 90)
			(size 1.8034 0.508)
			(layers "F.Cu" "F.Mask" "F.Paste")
			(net "GND")
		)
		(pad "148" smd rect
			(at 4.59994 2.549906 90)
			(size 1.8034 0.508)
			(layers "F.Cu" "F.Mask" "F.Paste")
			(net "M_K_DQ<4>")
		)
		(pad "149" smd rect
			(at 4.59994 3.400044 90)
			(size 1.8034 0.508)
			(layers "F.Cu" "F.Mask" "F.Paste")
			(net "GND")
		)
	)
)
